FILE_TYPE = CONNECTIVITY;
{Allegro Design Entry HDL 16.6-p007 (v16-6-112F) 10/10/2012}
"PAGE_NUMBER" = 131;
0"NC";
1"GND\g";
2"P1V05_PCH_STBY\g";
3"P1V05_PCH_STBY\g";
4"GND\g";
5"P1V05_PCH_STBY\g";
6"GND\g";
7"P1V05_PCH_STBY\g";
8"GND\g";
9"GND\g";
10"P1V05_PCH_STBY\g";
11"GND\g";
12"P1V05_PCH_STBY\g";
13"P1V05_PCH_STBY\g";
14"P1V05_PCH_STBY\g";
15"GND\g";
16"GND\g";
%"CAP_A"
"1","(975,4975)","0","dev_discrete","I1";
;
ROOM"SB_DECOUPLING"
$SEC"1"
CDS_SEC"1"
CDS_LIB"dev_discrete"
BOM_COST"SB"
CDS_LOCATION"C7B15"
MATERIAL"X6S"
VOLTAGE"4V"
PACK_TYPE"0603V"
TOLERANCE"20%"
VALUE"22.0UF"
PART_NUMBER"E15431-004"
LOCATION"C7B15";
"B"
$PN"2"16;
"A"
$PN"1"14;
%"CAP_A"
"1","(500,4025)","0","dev_discrete","I10";
;
ROOM"SB_DECOUPLING"
$SEC"1"
CDS_SEC"1"
CDS_LIB"dev_discrete"
BOM_COST"SB"
CDS_LOCATION"C7B22"
MATERIAL"X6S"
VOLTAGE"4V"
PACK_TYPE"0603V"
TOLERANCE"20%"
VALUE"22.0UF"
PART_NUMBER"E15431-004"
LOCATION"C7B22";
"B"
$PN"2"1;
"A"
$PN"1"2;
%"CAP_A"
"1","(50,4025)","0","dev_discrete","I11";
;
ROOM"SB_DECOUPLING"
$SEC"1"
CDS_SEC"1"
CDS_LIB"dev_discrete"
BOM_COST"SB"
CDS_LOCATION"C7B24"
MATERIAL"X6S"
VOLTAGE"4V"
PACK_TYPE"0603V"
TOLERANCE"20%"
VALUE"22.0UF"
PART_NUMBER"E15431-004"
LOCATION"C7B24";
"B"
$PN"2"1;
"A"
$PN"1"2;
%"CAP_A"
"1","(-425,4025)","0","dev_discrete","I12";
;
ROOM"SB_DECOUPLING"
$SEC"1"
CDS_SEC"1"
CDS_LIB"dev_discrete"
BOM_COST"SB"
CDS_LOCATION"C7B18"
MATERIAL"X6S"
VOLTAGE"4V"
PACK_TYPE"0603V"
TOLERANCE"20%"
VALUE"22.0UF"
PART_NUMBER"E15431-004"
LOCATION"C7B18";
"B"
$PN"2"1;
"A"
$PN"1"2;
%"GND"
"1","(275,3650)","0","mstr_symbols","I13";
;
HDL_POWER"GND"
ROOM"SB_DECOUPLING"
BODY_TYPE"PLUMBING"
BOM_COST"SB"
CDS_LIB"mstr_symbols"
SIZE"1B"
VOLTAGE"0";
"A\NAC"1;
%"CAP_A"
"1","(500,3025)","0","dev_discrete","I14";
;
ROOM"SB_DECOUPLING"
$SEC"1"
CDS_SEC"1"
CDS_LIB"dev_discrete"
BOM_COST"SB"
CDS_LOCATION"C8B9"
MATERIAL"X6S"
VOLTAGE"4V"
PACK_TYPE"0603V"
TOLERANCE"20%"
VALUE"22.0UF"
PART_NUMBER"E15431-004"
LOCATION"C8B9";
"B"
$PN"2"4;
"A"
$PN"1"3;
%"CAP_A"
"1","(50,3025)","0","dev_discrete","I15";
;
ROOM"SB_DECOUPLING"
$SEC"1"
CDS_SEC"1"
CDS_LIB"dev_discrete"
BOM_COST"SB"
CDS_LOCATION"C8B11"
MATERIAL"X6S"
VOLTAGE"4V"
PACK_TYPE"0603V"
TOLERANCE"20%"
VALUE"22.0UF"
PART_NUMBER"E15431-004"
LOCATION"C8B11";
"B"
$PN"2"4;
"A"
$PN"1"3;
%"CAP_A"
"1","(-400,3025)","0","dev_discrete","I16";
;
ROOM"SB_DECOUPLING"
$SEC"1"
CDS_SEC"1"
CDS_LIB"dev_discrete"
BOM_COST"SB"
CDS_LOCATION"C8B14"
MATERIAL"X6S"
VOLTAGE"4V"
PACK_TYPE"0603V"
TOLERANCE"20%"
VALUE"22.0UF"
PART_NUMBER"E15431-004"
LOCATION"C8B14";
"B"
$PN"2"4;
"A"
$PN"1"3;
%"P1V05_PCH_STBY"
"1","(-625,4300)","0","mstr_symbols","I17";
;
HDL_POWER"P1V05_PCH_STBY"
ROOM"SB_DECOUPLING"
BODY_TYPE"PLUMBING"
CDS_LIB"mstr_symbols"
BOM_COST"SB"
VOLTAGE"1.05V";
"G\NAC"2;
%"CAP_A"
"1","(-875,4025)","0","dev_discrete","I18";
;
ROOM"SB_DECOUPLING"
$SEC"1"
CDS_SEC"1"
CDS_LIB"dev_discrete"
BOM_COST"SB"
CDS_LOCATION"C7B17"
MATERIAL"X6S"
VOLTAGE"4V"
PACK_TYPE"0603V"
TOLERANCE"20%"
VALUE"22.0UF"
PART_NUMBER"E15431-004"
LOCATION"C7B17";
"B"
$PN"2"1;
"A"
$PN"1"2;
%"P1V05_PCH_STBY"
"1","(-625,3325)","0","mstr_symbols","I19";
;
HDL_POWER"P1V05_PCH_STBY"
ROOM"SB_DECOUPLING"
BODY_TYPE"PLUMBING"
CDS_LIB"mstr_symbols"
BOM_COST"SB"
VOLTAGE"1.05V";
"G\NAC"3;
%"CAP_A"
"1","(500,4975)","0","dev_discrete","I2";
;
ROOM"SB_DECOUPLING"
$SEC"1"
CDS_SEC"1"
CDS_LIB"dev_discrete"
BOM_COST"SB"
CDS_LOCATION"C7B19"
MATERIAL"X6S"
VOLTAGE"4V"
PACK_TYPE"0603V"
TOLERANCE"20%"
VALUE"22.0UF"
PART_NUMBER"E15431-004"
LOCATION"C7B19";
"B"
$PN"2"16;
"A"
$PN"1"14;
%"CAP_A"
"1","(-850,3025)","0","dev_discrete","I20";
;
ROOM"SB_DECOUPLING"
$SEC"1"
CDS_SEC"1"
CDS_LIB"dev_discrete"
BOM_COST"SB"
CDS_LOCATION"C8B13"
MATERIAL"X6S"
VOLTAGE"4V"
PACK_TYPE"0603V"
TOLERANCE"20%"
VALUE"22.0UF"
PART_NUMBER"E15431-004"
LOCATION"C8B13";
"B"
$PN"2"4;
"A"
$PN"1"3;
%"GND"
"1","(275,2675)","0","mstr_symbols","I21";
;
HDL_POWER"GND"
ROOM"SB_DECOUPLING"
BODY_TYPE"PLUMBING"
BOM_COST"SB"
CDS_LIB"mstr_symbols"
SIZE"1B"
VOLTAGE"0.0V";
"A\NAC"4;
%"CAP"
"1","(50,2025)","0","mstr_discrete","I22";
;
ROOM"SB_DECOUPLING"
CDS_LOCATION"C8B16"
$SEC"1"
CDS_SEC"1"
CDS_LIB"mstr_discrete"
BOM_COST"SB"
MATERIAL"X6S"
VOLTAGE"4V"
PACK_TYPE"0805"
TOLERANCE"20%"
VALUE"47UF"
PART_NUMBER"C95333-006"
LOCATION"C8B16";
"A"
$PN"1"5;
"B"
$PN"2"6;
%"P1V05_PCH_STBY"
"1","(-175,2325)","0","mstr_symbols","I23";
;
HDL_POWER"P1V05_PCH_STBY"
ROOM"SB_DECOUPLING"
BODY_TYPE"PLUMBING"
CDS_LIB"mstr_symbols"
BOM_COST"SB"
VOLTAGE"1.05V";
"G\NAC"5;
%"CAP"
"1","(-400,2025)","0","mstr_discrete","I24";
;
ROOM"SB_DECOUPLING"
CDS_LOCATION"C8B15"
$SEC"1"
CDS_SEC"1"
CDS_LIB"mstr_discrete"
BOM_COST"SB"
MATERIAL"X6S"
VOLTAGE"4V"
PACK_TYPE"0805"
TOLERANCE"20%"
VALUE"47UF"
PART_NUMBER"C95333-006"
LOCATION"C8B15";
"A"
$PN"1"5;
"B"
$PN"2"6;
%"GND"
"1","(-175,1650)","0","mstr_symbols","I25";
;
HDL_POWER"GND"
ROOM"SB_DECOUPLING"
BODY_TYPE"PLUMBING"
BOM_COST"SB"
CDS_LIB"mstr_symbols"
SIZE"1B"
VOLTAGE"0.0V";
"A\NAC"6;
%"P1V05_PCH_STBY"
"1","(-4575,5000)","0","mstr_symbols","I26";
;
HDL_POWER"P1V05_PCH_STBY"
ROOM"SB_DECOUPLING"
BODY_TYPE"PLUMBING"
CDS_LIB"mstr_symbols"
BOM_COST"SB"
VOLTAGE"1.05V";
"G\NAC"7;
%"CAP_A"
"1","(-2375,4725)","0","dev_discrete","I27";
;
ROOM"SB_DECOUPLING"
$SEC"1"
CDS_SEC"1"
CDS_LIB"dev_discrete"
BOM_COST"SB"
CDS_LOCATION"C2M22"
MATERIAL"X6S"
VOLTAGE"6.3V"
PACK_TYPE"0402V"
TOLERANCE"10%"
VALUE"1.0UF"
PART_NUMBER"D97712-004"
LOCATION"C2M22";
"B"
$PN"2"8;
"A"
$PN"1"7;
%"CAP_A"
"1","(-2800,4725)","0","dev_discrete","I28";
;
ROOM"SB_DECOUPLING"
$SEC"1"
CDS_SEC"1"
CDS_LIB"dev_discrete"
BOM_COST"SB"
CDS_LOCATION"C2M21"
MATERIAL"X6S"
VOLTAGE"6.3V"
PACK_TYPE"0402V"
TOLERANCE"10%"
VALUE"1.0UF"
PART_NUMBER"D97712-004"
LOCATION"C2M21";
"B"
$PN"2"8;
"A"
$PN"1"7;
%"CAP_A"
"1","(-3175,4725)","0","dev_discrete","I29";
;
ROOM"SB_DECOUPLING"
$SEC"1"
CDS_SEC"1"
CDS_LIB"dev_discrete"
BOM_COST"SB"
CDS_LOCATION"C2M18"
MATERIAL"X6S"
VOLTAGE"6.3V"
PACK_TYPE"0402V"
TOLERANCE"10%"
VALUE"1.0UF"
PART_NUMBER"D97712-004"
LOCATION"C2M18";
"B"
$PN"2"8;
"A"
$PN"1"7;
%"CAP_A"
"1","(50,4975)","0","dev_discrete","I3";
;
ROOM"SB_DECOUPLING"
$SEC"1"
CDS_SEC"1"
CDS_LIB"dev_discrete"
BOM_COST"SB"
CDS_LOCATION"C7B16"
MATERIAL"X6S"
VOLTAGE"4V"
PACK_TYPE"0603V"
TOLERANCE"20%"
VALUE"22.0UF"
PART_NUMBER"E15431-004"
LOCATION"C7B16";
"B"
$PN"2"16;
"A"
$PN"1"14;
%"GND"
"1","(-3350,4375)","0","mstr_symbols","I30";
;
HDL_POWER"GND"
ROOM"SB_DECOUPLING"
BODY_TYPE"PLUMBING"
CDS_LIB"mstr_symbols"
SIZE"1B"
BOM_COST"SB"
VOLTAGE"0";
"A\NAC"8;
%"CAP_A"
"1","(-2850,3525)","0","dev_discrete","I31";
;
ROOM"SB_DECOUPLING"
$SEC"1"
CDS_SEC"1"
CDS_LIB"dev_discrete"
BOM_COST"SB"
CDS_LOCATION"C2M19"
MATERIAL"X6S"
VOLTAGE"6.3V"
PACK_TYPE"0402V"
TOLERANCE"10%"
VALUE"1.0UF"
PART_NUMBER"D97712-004"
LOCATION"C2M19";
"B"
$PN"2"9;
"A"
$PN"1"12;
%"CAP_A"
"1","(-3225,3525)","0","dev_discrete","I32";
;
ROOM"SB_DECOUPLING"
$SEC"1"
CDS_SEC"1"
CDS_LIB"dev_discrete"
BOM_COST"SB"
CDS_LOCATION"C3M38"
MATERIAL"X6S"
VOLTAGE"6.3V"
PACK_TYPE"0402V"
TOLERANCE"10%"
VALUE"1.0UF"
PART_NUMBER"D97712-004"
LOCATION"C3M38";
"B"
$PN"2"9;
"A"
$PN"1"12;
%"GND"
"1","(-3425,3175)","0","mstr_symbols","I33";
;
HDL_POWER"GND"
ROOM"SB_DECOUPLING"
BODY_TYPE"PLUMBING"
BOM_COST"SB"
CDS_LIB"mstr_symbols"
SIZE"1B"
VOLTAGE"0";
"A\NAC"9;
%"CAP"
"1","(-2400,2025)","0","mstr_discrete","I34";
;
ROOM"SB_DECOUPLING"
CDS_LOCATION"C2M17"
$SEC"1"
CDS_SEC"1"
BOM_COST"SB"
CDS_LIB"mstr_discrete"
MATERIAL"X6S"
VOLTAGE"4V"
PACK_TYPE"0805"
TOLERANCE"20%"
VALUE"47UF"
PART_NUMBER"C95333-006"
LOCATION"C2M17";
"A"
$PN"1"10;
"B"
$PN"2"11;
%"CAP"
"1","(-2800,2025)","0","mstr_discrete","I35";
;
ROOM"SB_DECOUPLING"
CDS_LOCATION"C2M11"
$SEC"1"
CDS_SEC"1"
CDS_LIB"mstr_discrete"
BOM_COST"SB"
MATERIAL"X6S"
VOLTAGE"4V"
PACK_TYPE"0805"
TOLERANCE"20%"
VALUE"47UF"
PART_NUMBER"C95333-006"
LOCATION"C2M11";
"A"
$PN"1"10;
"B"
$PN"2"11;
%"P1V05_PCH_STBY"
"1","(-3025,2325)","0","mstr_symbols","I36";
;
HDL_POWER"P1V05_PCH_STBY"
ROOM"SB_DECOUPLING"
BODY_TYPE"PLUMBING"
CDS_LIB"mstr_symbols"
BOM_COST"SB"
VOLTAGE"1.05V";
"G\NAC"10;
%"CAP"
"1","(-3250,2025)","0","mstr_discrete","I37";
;
ROOM"SB_DECOUPLING"
CDS_LOCATION"C8A13"
$SEC"1"
CDS_SEC"1"
BOM_COST"SB"
CDS_LIB"mstr_discrete"
MATERIAL"X6S"
VOLTAGE"4V"
PACK_TYPE"0805"
TOLERANCE"20%"
VALUE"47UF"
PART_NUMBER"C95333-006"
LOCATION"C8A13";
"A"
$PN"1"10;
"B"
$PN"2"11;
%"GND"
"1","(-3025,1650)","0","mstr_symbols","I38";
;
HDL_POWER"GND"
ROOM"SB_DECOUPLING"
BODY_TYPE"PLUMBING"
SIZE"1B"
CDS_LIB"mstr_symbols"
BOM_COST"SB"
VOLTAGE"0.0V";
"A\NAC"11;
%"CAP_A"
"1","(-3550,4725)","0","dev_discrete","I39";
;
ROOM"SB_DECOUPLING"
$SEC"1"
CDS_SEC"1"
CDS_LIB"dev_discrete"
BOM_COST"SB"
CDS_LOCATION"C2M20"
MATERIAL"X6S"
VOLTAGE"6.3V"
PACK_TYPE"0402V"
TOLERANCE"10%"
VALUE"1.0UF"
PART_NUMBER"D97712-004"
LOCATION"C2M20";
"B"
$PN"2"8;
"A"
$PN"1"7;
%"CAP_A"
"1","(-425,4975)","0","dev_discrete","I4";
;
ROOM"SB_DECOUPLING"
$SEC"1"
CDS_SEC"1"
CDS_LIB"dev_discrete"
BOM_COST"SB"
CDS_LOCATION"C7B21"
MATERIAL"X6S"
VOLTAGE"4V"
PACK_TYPE"0603V"
TOLERANCE"20%"
VALUE"22.0UF"
PART_NUMBER"E15431-004"
LOCATION"C7B21";
"B"
$PN"2"16;
"A"
$PN"1"14;
%"CAP_A"
"1","(-3950,4725)","0","dev_discrete","I40";
;
ROOM"SB_DECOUPLING"
$SEC"1"
CDS_SEC"1"
CDS_LIB"dev_discrete"
BOM_COST"SB"
CDS_LOCATION"C2N13"
MATERIAL"X6S"
VOLTAGE"6.3V"
PACK_TYPE"0402V"
TOLERANCE"10%"
VALUE"1.0UF"
PART_NUMBER"D97712-004"
LOCATION"C2N13";
"B"
$PN"2"8;
"A"
$PN"1"7;
%"CAP_A"
"1","(-4350,4725)","0","dev_discrete","I41";
;
ROOM"SB_DECOUPLING"
$SEC"1"
CDS_SEC"1"
CDS_LIB"dev_discrete"
BOM_COST"SB"
CDS_LOCATION"C2N2"
MATERIAL"X6S"
VOLTAGE"6.3V"
PACK_TYPE"0402V"
TOLERANCE"10%"
VALUE"1.0UF"
PART_NUMBER"D97712-004"
LOCATION"C2N2";
"B"
$PN"2"8;
"A"
$PN"1"7;
%"CAP_A"
"1","(-3600,3525)","0","dev_discrete","I42";
;
ROOM"SB_DECOUPLING"
$SEC"1"
CDS_SEC"1"
CDS_LIB"dev_discrete"
BOM_COST"SB"
CDS_LOCATION"C3M43"
MATERIAL"X6S"
VOLTAGE"6.3V"
PACK_TYPE"0402V"
TOLERANCE"10%"
VALUE"1.0UF"
PART_NUMBER"D97712-004"
LOCATION"C3M43";
"B"
$PN"2"9;
"A"
$PN"1"12;
%"CAP_A"
"1","(-4000,3525)","0","dev_discrete","I43";
;
ROOM"SB_DECOUPLING"
$SEC"1"
CDS_SEC"1"
CDS_LIB"dev_discrete"
BOM_COST"SB"
CDS_LOCATION"C2N7"
MATERIAL"X6S"
VOLTAGE"6.3V"
PACK_TYPE"0402V"
TOLERANCE"10%"
VALUE"1.0UF"
PART_NUMBER"D97712-004"
LOCATION"C2N7";
"B"
$PN"2"9;
"A"
$PN"1"12;
%"CAP_A"
"1","(-4375,3525)","0","dev_discrete","I44";
;
ROOM"SB_DECOUPLING"
$SEC"1"
CDS_SEC"1"
CDS_LIB"dev_discrete"
BOM_COST"SB"
CDS_LOCATION"C3M39"
MATERIAL"X6S"
VOLTAGE"6.3V"
PACK_TYPE"0402V"
TOLERANCE"10%"
VALUE"1.0UF"
PART_NUMBER"D97712-004"
LOCATION"C3M39";
"B"
$PN"2"9;
"A"
$PN"1"12;
%"CAP_A"
"1","(-4750,4725)","0","dev_discrete","I45";
;
ROOM"SB_DECOUPLING"
$SEC"1"
CDS_SEC"1"
CDS_LIB"dev_discrete"
BOM_COST"SB"
CDS_LOCATION"C3M42"
MATERIAL"X6S"
VOLTAGE"6.3V"
PACK_TYPE"0402V"
TOLERANCE"10%"
VALUE"1.0UF"
PART_NUMBER"D97712-004"
LOCATION"C3M42";
"B"
$PN"2"8;
"A"
$PN"1"7;
%"P1V05_PCH_STBY"
"1","(-4600,3775)","0","mstr_symbols","I46";
;
HDL_POWER"P1V05_PCH_STBY"
ROOM"SB_DECOUPLING"
BODY_TYPE"PLUMBING"
CDS_LIB"mstr_symbols"
BOM_COST"SB"
VOLTAGE"1.05V";
"G\NAC"12;
%"CAP_A"
"1","(-4775,3525)","0","dev_discrete","I47";
;
ROOM"SB_DECOUPLING"
$SEC"1"
CDS_SEC"1"
CDS_LIB"dev_discrete"
BOM_COST"SB"
CDS_LOCATION"C2N8"
MATERIAL"X6S"
VOLTAGE"6.3V"
PACK_TYPE"0402V"
TOLERANCE"10%"
VALUE"1.0UF"
PART_NUMBER"D97712-004"
LOCATION"C2N8";
"B"
$PN"2"9;
"A"
$PN"1"12;
%"CAP_A"
"1","(-4250,2100)","0","dev_discrete","I48";
;
ROOM"SB_DECOUPLING"
$SEC"1"
CDS_SEC"1"
CDS_LIB"dev_discrete"
BOM_COST"SB"
CDS_LOCATION"C2M13"
MATERIAL"X6S"
VOLTAGE"4V"
PACK_TYPE"0603V"
TOLERANCE"20%"
VALUE"22.0UF"
PART_NUMBER"E15431-004"
LOCATION"C2M13";
"B"
$PN"2"15;
"A"
$PN"1"13;
%"P1V05_PCH_STBY"
"1","(-4800,2400)","0","mstr_symbols","I49";
;
HDL_POWER"P1V05_PCH_STBY"
ROOM"SB_DECOUPLING"
BODY_TYPE"PLUMBING"
CDS_LIB"mstr_symbols"
BOM_COST"SB"
VOLTAGE"1.05V";
"G\NAC"13;
%"P1V05_PCH_STBY"
"1","(-600,5225)","0","mstr_symbols","I5";
;
HDL_POWER"P1V05_PCH_STBY"
ROOM"SB_DECOUPLING"
BODY_TYPE"PLUMBING"
CDS_LIB"mstr_symbols"
BOM_COST"SB"
VOLTAGE"1.05V";
"G\NAC"14;
%"CAP_A"
"1","(-4650,2100)","0","dev_discrete","I50";
;
ROOM"SB_DECOUPLING"
$SEC"1"
CDS_SEC"1"
CDS_LIB"dev_discrete"
BOM_COST"SB"
CDS_LOCATION"C2N10"
MATERIAL"X6S"
VOLTAGE"4V"
PACK_TYPE"0603V"
TOLERANCE"20%"
VALUE"22.0UF"
PART_NUMBER"E15431-004"
LOCATION"C2N10";
"B"
$PN"2"15;
"A"
$PN"1"13;
%"GND"
"1","(-4800,1725)","0","mstr_symbols","I51";
;
HDL_POWER"GND"
ROOM"SB_DECOUPLING"
BODY_TYPE"PLUMBING"
BOM_COST"SB"
SIZE"1B"
CDS_LIB"mstr_symbols"
VOLTAGE"0.0V";
"A\NAC"15;
%"CAP_A"
"1","(-5075,2100)","0","dev_discrete","I52";
;
ROOM"SB_DECOUPLING"
$SEC"1"
CDS_SEC"1"
CDS_LIB"dev_discrete"
BOM_COST"SB"
CDS_LOCATION"C2M12"
MATERIAL"X6S"
VOLTAGE"4V"
PACK_TYPE"0603V"
TOLERANCE"20%"
VALUE"22.0UF"
PART_NUMBER"E15431-004"
LOCATION"C2M12";
"B"
$PN"2"15;
"A"
$PN"1"13;
%"CAP_A"
"1","(-875,4975)","0","dev_discrete","I6";
;
ROOM"SB_DECOUPLING"
$SEC"1"
CDS_SEC"1"
CDS_LIB"dev_discrete"
BOM_COST"SB"
CDS_LOCATION"C7B20"
MATERIAL"X6S"
VOLTAGE"4V"
PACK_TYPE"0603V"
TOLERANCE"20%"
VALUE"22.0UF"
PART_NUMBER"E15431-004"
LOCATION"C7B20";
"B"
$PN"2"16;
"A"
$PN"1"14;
%"CAP_A"
"1","(975,4025)","0","dev_discrete","I7";
;
ROOM"SB_DECOUPLING"
$SEC"1"
CDS_SEC"1"
CDS_LIB"dev_discrete"
BOM_COST"SB"
CDS_LOCATION"C7B23"
MATERIAL"X6S"
VOLTAGE"4V"
PACK_TYPE"0603V"
TOLERANCE"20%"
VALUE"22.0UF"
PART_NUMBER"E15431-004"
LOCATION"C7B23";
"B"
$PN"2"1;
"A"
$PN"1"2;
%"CAP_A"
"1","(950,3025)","0","dev_discrete","I8";
;
ROOM"SB_DECOUPLING"
$SEC"1"
CDS_SEC"1"
CDS_LIB"dev_discrete"
BOM_COST"SB"
CDS_LOCATION"C8B10"
MATERIAL"X6S"
VOLTAGE"4V"
PACK_TYPE"0603V"
TOLERANCE"20%"
VALUE"22.0UF"
PART_NUMBER"E15431-004"
LOCATION"C8B10";
"B"
$PN"2"4;
"A"
$PN"1"3;
%"GND"
"1","(275,4625)","0","mstr_symbols","I9";
;
HDL_POWER"GND"
ROOM"SB_DECOUPLING"
BODY_TYPE"PLUMBING"
BOM_COST"SB"
CDS_LIB"mstr_symbols"
SIZE"1B"
VOLTAGE"0";
"A\NAC"16;
END.
